# TIMECARD (Time Appliance Project (Time Card)) — schematic netlist excerpt (pin names and nets, part order shuffled) for the footprints in the layout excerpt that follows; sources: Cadence DE-HDL packaged netlist, KiCad conversion of R4006-B0001-02_R01.brd

R434  RESISTOR  33OHM 1%  pkg SMC_0402R_H016  page 25 : \1\ = UNNAMED_16_CONNHDR2X6FSSMT_I1_1 ; \2\ = FPGA_IO_0
C62  CAPACITOR  0.1UF 25V 10%  pkg SMC_0402R_H022  page 21 : \1\ = XP5R0V ; \2\ = SG

(kicad_pcb
	(version 20260206)
	(generator "pcbnew")
	(generator_version "10.0")
	(general
		(thickness 1.6)
		(legacy_teardrops no)
	)
	(paper "A4")
	(title_block
		(title "timecard-production-celestica-r4006 — R4006-B0001-02_R01.brd")
		(comment 1 "Time Appliance Project (Time Card) / footprints 800-801 of 1113")
	)
	(layers
		(0 "F.Cu" signal "TOP")
		(4 "In1.Cu" signal "L02_GND1")
		(6 "In2.Cu" signal "L03_SIG1")
		(8 "In3.Cu" signal "L04_GND2")
		(10 "In4.Cu" signal "L05_VCC1")
		(12 "In5.Cu" signal "L06_VCC2")
		(14 "In6.Cu" signal "L07_GND3")
		(16 "In7.Cu" signal "L08_SIG2")
		(18 "In8.Cu" signal "L09_GND4")
		(2 "B.Cu" signal "BOTTOM")
		(9 "F.Adhes" user "F.Adhesive")
		(11 "B.Adhes" user "B.Adhesive")
		(13 "F.Paste" user "Package Geometry/Pastemask Top")
		(15 "B.Paste" user "Package Geometry/Pastemask Bottom")
		(5 "F.SilkS" user "Ref Des/Silkscreen Top")
		(7 "B.SilkS" user "Ref Des/Silkscreen Bottom")
		(1 "F.Mask" user "Board Geometry/Soldermask Top")
		(3 "B.Mask" user "Board Geometry/Soldermask Bottom")
		(17 "Dwgs.User" user "User.Drawings")
		(19 "Cmts.User" user "User.Comments")
		(21 "Eco1.User" user "User.Eco1")
		(23 "Eco2.User" user "User.Eco2")
		(25 "Edge.Cuts" user "Board Geometry/Outline")
		(27 "Margin" user)
		(31 "F.CrtYd" user "Package Geometry/Place Bound Top")
		(29 "B.CrtYd" user "Package Geometry/Place Bound Bottom")
		(35 "F.Fab" user "Ref Des/Assembly Top")
		(33 "B.Fab" user "Ref Des/Assembly Bottom")
	)
	(footprint ""
		(layer "B.Cu")
		(at 82.423 -73.152 90)
		(property "Reference" "C62"
			(at -0.508 1.23063 270)
			(unlocked yes)
			(layer "B.SilkS")
			(effects
				(font
					(size 0.7874 0.5842)
					(thickness 0.1524)
				)
				(justify mirror)
			)
		)
		(property "Value" "VAL*"
			(at -0.0762 2.067306 90)
			(unlocked yes)
			(layer "B.Fab")
			(hide yes)
			(effects
				(font
					(size 0.7874 0.5842)
					(thickness 0.1524)
				)
				(justify mirror)
			)
		)
		(property "Tolerance" "TOL*"
			(at -0.0762 3.032506 90)
			(unlocked yes)
			(layer "Cmts.User")
			(hide yes)
			(effects
				(font
					(size 0.7874 0.5842)
					(thickness 0.1524)
				)
				(justify mirror)
			)
		)
		(property "User Part Number" "PARTNUM*"
			(at -0.1016 4.023106 90)
			(unlocked yes)
			(layer "Cmts.User")
			(hide yes)
			(effects
				(font
					(size 0.7874 0.5842)
					(thickness 0.1524)
				)
				(justify mirror)
			)
		)
		(property "Device Type" "CAPACITOR-G105-0B104-EK,0.1UF,A"
			(at -0.0508 1.127506 90)
			(unlocked yes)
			(layer "B.Fab")
			(hide yes)
			(effects
				(font
					(size 0.7874 0.5842)
					(thickness 0.1524)
				)
				(justify mirror)
			)
		)
		(duplicate_pad_numbers_are_jumpers no)
		(fp_line
			(start 1.143 -0.5588)
			(end 1.143 0.5588)
			(stroke
				(width 0.1)
				(type default)
			)
			(layer "B.SilkS")
		)
		(fp_line
			(start -1.143 -0.5588)
			(end 1.143 -0.5588)
			(stroke
				(width 0.1)
				(type default)
			)
			(layer "B.SilkS")
		)
		(fp_line
			(start 1.143 0.5588)
			(end -1.143 0.5588)
			(stroke
				(width 0.1)
				(type default)
			)
			(layer "B.SilkS")
		)
		(fp_line
			(start -1.143 0.5588)
			(end -1.143 -0.5588)
			(stroke
				(width 0.1)
				(type default)
			)
			(layer "B.SilkS")
		)
		(fp_rect
			(start -1.143 -0.5588)
			(end 1.143 0.5588)
			(stroke
				(width 0)
				(type default)
			)
			(fill no)
			(layer "B.CrtYd")
		)
		(fp_line
			(start 0.508 -0.3048)
			(end 0.508 0.3048)
			(stroke
				(width 0.1)
				(type default)
			)
			(layer "B.Fab")
		)
		(fp_line
			(start -0.508 -0.3048)
			(end 0.508 -0.3048)
			(stroke
				(width 0.1)
				(type default)
			)
			(layer "B.Fab")
		)
		(fp_line
			(start 0.508 0.3048)
			(end -0.508 0.3048)
			(stroke
				(width 0.1)
				(type default)
			)
			(layer "B.Fab")
		)
		(fp_line
			(start -0.508 0.3048)
			(end -0.508 -0.3048)
			(stroke
				(width 0.1)
				(type default)
			)
			(layer "B.Fab")
		)
		(pad "1" smd rect
			(at 0.5334 0 270)
			(size 0.7112 0.6096)
			(layers "B.Cu" "B.Mask" "B.Paste")
			(net "XP5R0V")
		)
		(pad "2" smd rect
			(at -0.5334 0 270)
			(size 0.7112 0.6096)
			(layers "B.Cu" "B.Mask" "B.Paste")
			(net "SG")
		)
		(zone
			(layer "B.Cu")
			(hatch none 0.5)
			(connect_pads
				(clearance 0)
			)
			(min_thickness 0.25)
			(keepout
				(tracks allowed)
				(vias not_allowed)
				(pads allowed)
				(copperpour not_allowed)
				(footprints allowed)
			)
			(placement
				(enabled no)
				(sheetname "")
			)
			(fill
				(thermal_gap 0.5)
				(thermal_bridge_width 0.5)
				(island_removal_mode 0)
			)
			(polygon
				(pts
					(xy 82.1182 -73.0758) (xy 82.7278 -73.0758) (xy 82.7278 -73.2282) (xy 82.1182 -73.2282)
				)
			)
		)
	)
	(footprint ""
		(layer "B.Cu")
		(at 151.892 -44.704 90)
		(property "Reference" "R434"
			(at -9.94537 0.635 0)
			(unlocked yes)
			(layer "B.SilkS")
			(effects
				(font
					(size 0.7874 0.5842)
					(thickness 0.1524)
				)
				(justify mirror)
			)
		)
		(property "Value" "VAL*"
			(at -0.02032 2.13233 90)
			(unlocked yes)
			(layer "B.Fab")
			(hide yes)
			(effects
				(font
					(size 0.7874 0.5842)
					(thickness 0.1524)
				)
				(justify mirror)
			)
		)
		(property "Tolerance" "TOL*"
			(at -0.044704 3.05435 90)
			(unlocked yes)
			(layer "Cmts.User")
			(hide yes)
			(effects
				(font
					(size 0.7874 0.5842)
					(thickness 0.1524)
				)
				(justify mirror)
			)
		)
		(property "User Part Number" "PARTNUM*"
			(at -0.02032 4.024884 90)
			(unlocked yes)
			(layer "Cmts.User")
			(hide yes)
			(effects
				(font
					(size 0.7874 0.5842)
					(thickness 0.1524)
				)
				(justify mirror)
			)
		)
		(property "Device Type" "RESISTOR-G155-133R0-01,33OHM,1%"
			(at -0.008382 1.210564 90)
			(unlocked yes)
			(layer "B.Fab")
			(hide yes)
			(effects
				(font
					(size 0.7874 0.5842)
					(thickness 0.1524)
				)
				(justify mirror)
			)
		)
		(duplicate_pad_numbers_are_jumpers no)
		(fp_line
			(start 1.143 -0.5588)
			(end 1.143 0.5588)
			(stroke
				(width 0.1)
				(type default)
			)
			(layer "B.SilkS")
		)
		(fp_line
			(start -1.143 -0.5588)
			(end 1.143 -0.5588)
			(stroke
				(width 0.1)
				(type default)
			)
			(layer "B.SilkS")
		)
		(fp_line
			(start 1.143 0.5588)
			(end -1.143 0.5588)
			(stroke
				(width 0.1)
				(type default)
			)
			(layer "B.SilkS")
		)
		(fp_line
			(start -1.143 0.5588)
			(end -1.143 -0.5588)
			(stroke
				(width 0.1)
				(type default)
			)
			(layer "B.SilkS")
		)
		(fp_poly
			(pts
				(xy 1.143 0.5588) (xy -1.143 0.5588) (xy -1.143 -0.5588) (xy 1.143 -0.5588)
			)
			(stroke
				(width 0)
				(type default)
			)
			(fill no)
			(layer "B.CrtYd")
		)
		(fp_line
			(start 0.508 -0.3048)
			(end 0.508 0.3048)
			(stroke
				(width 0.1)
				(type default)
			)
			(layer "B.Fab")
		)
		(fp_line
			(start -0.508 -0.3048)
			(end 0.508 -0.3048)
			(stroke
				(width 0.1)
				(type default)
			)
			(layer "B.Fab")
		)
		(fp_line
			(start 0.508 0.3048)
			(end -0.508 0.3048)
			(stroke
				(width 0.1)
				(type default)
			)
			(layer "B.Fab")
		)
		(fp_line
			(start -0.508 0.3048)
			(end -0.508 -0.3048)
			(stroke
				(width 0.1)
				(type default)
			)
			(layer "B.Fab")
		)
		(pad "1" smd rect
			(at 0.5334 0 270)
			(size 0.7112 0.6096)
			(layers "B.Cu" "B.Mask" "B.Paste")
			(net "UNNAMED_16_CONNHDR2X6FSSMT_I1_1")
		)
		(pad "2" smd rect
			(at -0.5334 0 270)
			(size 0.7112 0.6096)
			(layers "B.Cu" "B.Mask" "B.Paste")
			(net "FPGA_IO_0")
		)
		(zone
			(layer "B.Cu")
			(hatch none 0.5)
			(connect_pads
				(clearance 0)
			)
			(min_thickness 0.25)
			(keepout
				(tracks allowed)
				(vias not_allowed)
				(pads allowed)
				(copperpour not_allowed)
				(footprints allowed)
			)
			(placement
				(enabled no)
				(sheetname "")
			)
			(fill
				(thermal_gap 0.5)
				(thermal_bridge_width 0.5)
				(island_removal_mode 0)
			)
			(polygon
				(pts
					(xy 152.1968 -44.7802) (xy 151.5872 -44.7802) (xy 151.5872 -44.6278) (xy 152.1968 -44.6278)
				)
			)
		)
		(zone
			(layer "B.Cu")
			(hatch none 0.5)
			(connect_pads
				(clearance 0)
			)
			(min_thickness 0.25)
			(keepout
				(tracks not_allowed)
				(vias allowed)
				(pads allowed)
				(copperpour not_allowed)
				(footprints allowed)
			)
			(placement
				(enabled no)
				(sheetname "")
			)
			(fill
				(thermal_gap 0.5)
				(thermal_bridge_width 0.5)
				(island_removal_mode 0)
			)
			(polygon
				(pts
					(xy 152.1968 -44.7802) (xy 151.5872 -44.7802) (xy 151.5872 -44.6278) (xy 152.1968 -44.6278)
				)
			)
		)
	)
)
